(kicad_pcb
	(version 20260206)
	(generator "pcbnew")
	(generator_version "10.0")
	(general
		(thickness 1.6)
		(legacy_teardrops no)
	)
	(paper "A4")
	(title_block
		(title "timecard-production-celestica-r4006 — R4006-B0001-02_R01.brd")
		(comment 1 "Time Appliance Project (Time Card) / footprints 174-180 of 1113")
	)
	(layers
		(0 "F.Cu" signal "TOP")
		(4 "In1.Cu" signal "L02_GND1")
		(6 "In2.Cu" signal "L03_SIG1")
		(8 "In3.Cu" signal "L04_GND2")
		(10 "In4.Cu" signal "L05_VCC1")
		(12 "In5.Cu" signal "L06_VCC2")
		(14 "In6.Cu" signal "L07_GND3")
		(16 "In7.Cu" signal "L08_SIG2")
		(18 "In8.Cu" signal "L09_GND4")
		(2 "B.Cu" signal "BOTTOM")
		(9 "F.Adhes" user "F.Adhesive")
		(11 "B.Adhes" user "B.Adhesive")
		(13 "F.Paste" user "Package Geometry/Pastemask Top")
		(15 "B.Paste" user "Package Geometry/Pastemask Bottom")
		(5 "F.SilkS" user "Ref Des/Silkscreen Top")
		(7 "B.SilkS" user "Ref Des/Silkscreen Bottom")
		(1 "F.Mask" user "Board Geometry/Soldermask Top")
		(3 "B.Mask" user "Board Geometry/Soldermask Bottom")
		(17 "Dwgs.User" user "User.Drawings")
		(19 "Cmts.User" user "User.Comments")
		(21 "Eco1.User" user "User.Eco1")
		(23 "Eco2.User" user "User.Eco2")
		(25 "Edge.Cuts" user "Board Geometry/Outline")
		(27 "Margin" user)
		(31 "F.CrtYd" user "Package Geometry/Place Bound Top")
		(29 "B.CrtYd" user "Package Geometry/Place Bound Bottom")
		(35 "F.Fab" user "Ref Des/Assembly Top")
		(33 "B.Fab" user "Ref Des/Assembly Bottom")
	)
	(footprint ""
		(layer "F.Cu")
		(at 4.073906 -32.599884)
		(property "Reference" "J1"
			(at 5.324094 -1.142746 0)
			(unlocked yes)
			(layer "F.SilkS")
			(effects
				(font
					(size 0.7874 0.5842)
					(thickness 0.1524)
				)
			)
		)
		(property "Value" ""
			(at 0 0 0)
			(layer "F.Fab")
			(effects
				(font
					(size 1.27 1.27)
				)
			)
		)
		(property "Device Type" "CONN_JACK_1P_GH4_S_TH-G200-130A"
			(at -5.098288 5.899912 0)
			(unlocked yes)
			(layer "F.Fab")
			(hide yes)
			(effects
				(font
					(size 0.7874 0.5842)
					(thickness 0.1524)
				)
			)
		)
		(property "User Part Number" "PARTNUM*"
			(at -5.098288 7.093712 0)
			(unlocked yes)
			(layer "Cmts.User")
			(hide yes)
			(effects
				(font
					(size 0.7874 0.5842)
					(thickness 0.1524)
				)
			)
		)
		(duplicate_pad_numbers_are_jumpers no)
		(fp_line
			(start -13.953998 -3.937)
			(end 3.937 -3.937)
			(stroke
				(width 0.1)
				(type default)
			)
			(layer "F.SilkS")
		)
		(fp_line
			(start -13.953998 3.937)
			(end -13.953998 -3.937)
			(stroke
				(width 0.1)
				(type default)
			)
			(layer "F.SilkS")
		)
		(fp_line
			(start 3.937 -3.937)
			(end 3.937 3.937)
			(stroke
				(width 0.1)
				(type default)
			)
			(layer "F.SilkS")
		)
		(fp_line
			(start 3.937 3.937)
			(end -13.953998 3.937)
			(stroke
				(width 0.1)
				(type default)
			)
			(layer "F.SilkS")
		)
		(fp_rect
			(start -8.763 8.763)
			(end 8.763 -8.763)
			(stroke
				(width 0)
				(type default)
			)
			(fill no)
			(layer "B.CrtYd")
		)
		(fp_rect
			(start -14.207998 4.191)
			(end 4.191 -4.191)
			(stroke
				(width 0)
				(type default)
			)
			(fill no)
			(layer "F.CrtYd")
		)
		(fp_line
			(start -13.699998 -3.599942)
			(end 3.599942 -3.599942)
			(stroke
				(width 0.1)
				(type default)
			)
			(layer "F.Fab")
		)
		(fp_line
			(start -13.699998 3.599942)
			(end -13.699998 -3.599942)
			(stroke
				(width 0.1)
				(type default)
			)
			(layer "F.Fab")
		)
		(fp_line
			(start 3.599942 -3.599942)
			(end 3.599942 3.599942)
			(stroke
				(width 0.1)
				(type default)
			)
			(layer "F.Fab")
		)
		(fp_line
			(start 3.599942 3.599942)
			(end -13.699998 3.599942)
			(stroke
				(width 0.1)
				(type default)
			)
			(layer "F.Fab")
		)
		(fp_text user "GH3"
			(at -1.533906 4.310634 0)
			(unlocked yes)
			(layer "F.SilkS")
			(effects
				(font
					(size 0.635 0.4064)
					(thickness 0.1524)
				)
			)
		)
		(fp_text user "GH1"
			(at -0.009906 -4.325366 0)
			(unlocked yes)
			(layer "F.SilkS")
			(effects
				(font
					(size 0.635 0.4064)
					(thickness 0.1524)
				)
			)
		)
		(fp_text user "GH4"
			(at 2.276094 4.437634 0)
			(unlocked yes)
			(layer "F.SilkS")
			(effects
				(font
					(size 0.635 0.4064)
					(thickness 0.1524)
				)
			)
		)
		(fp_text user "GH2"
			(at 2.54 -4.50215 0)
			(unlocked yes)
			(layer "F.SilkS")
			(effects
				(font
					(size 0.635 0.4064)
					(thickness 0.1524)
				)
			)
		)
		(fp_text user "1"
			(at 4.015994 0.000254 0)
			(unlocked yes)
			(layer "F.SilkS")
			(effects
				(font
					(size 0.7874 0.5842)
					(thickness 0.1524)
				)
				(justify left)
			)
		)
		(fp_text user "GH3"
			(at -2.803906 4.201668 0)
			(unlocked yes)
			(layer "F.Fab")
			(effects
				(font
					(size 0.7874 0.5842)
					(thickness 0.1524)
				)
			)
		)
		(fp_text user "GH1"
			(at -2.676906 -4.063746 0)
			(unlocked yes)
			(layer "F.Fab")
			(effects
				(font
					(size 0.7874 0.5842)
					(thickness 0.1524)
				)
			)
		)
		(fp_text user "GH2"
			(at 2.54 -4.57073 0)
			(unlocked yes)
			(layer "F.Fab")
			(effects
				(font
					(size 0.7874 0.5842)
					(thickness 0.1524)
				)
			)
		)
		(fp_text user "GH4"
			(at 2.657094 4.191254 0)
			(unlocked yes)
			(layer "F.Fab")
			(effects
				(font
					(size 0.7874 0.5842)
					(thickness 0.1524)
				)
			)
		)
		(fp_text user "1"
			(at 4.191 -0.35433 0)
			(unlocked yes)
			(layer "F.Fab")
			(effects
				(font
					(size 0.7874 0.5842)
					(thickness 0.1524)
				)
				(justify left)
			)
		)
		(pad "1" thru_hole circle
			(at 0 0)
			(size 2.1844 2.1844)
			(drill 1.4986)
			(layers "*.Cu" "*.Mask")
			(remove_unused_layers no)
			(net "SMA3_SIG_IO_CONN")
			(padstack
				(mode front_inner_back)
				(layer "Inner"
					(shape circle)
					(size 2.1844 2.1844)
					(clearance -0.0508)
				)
				(layer "B.Cu"
					(shape circle)
					(size 2.1844 2.1844)
				)
			)
		)
		(pad "GH1" thru_hole circle
			(at -2.54 -2.54)
			(size 2.286 2.286)
			(drill 1.6002)
			(layers "*.Cu" "*.Mask")
			(remove_unused_layers no)
			(net "SG")
			(padstack
				(mode front_inner_back)
				(layer "Inner"
					(shape circle)
					(size 2.286 2.286)
					(clearance -0.0508)
				)
				(layer "B.Cu"
					(shape circle)
					(size 2.286 2.286)
				)
			)
		)
		(pad "GH2" thru_hole circle
			(at 2.54 -2.54)
			(size 2.286 2.286)
			(drill 1.6002)
			(layers "*.Cu" "*.Mask")
			(remove_unused_layers no)
			(net "SG")
			(padstack
				(mode front_inner_back)
				(layer "Inner"
					(shape circle)
					(size 2.286 2.286)
					(clearance -0.0508)
				)
				(layer "B.Cu"
					(shape circle)
					(size 2.286 2.286)
				)
			)
		)
		(pad "GH3" thru_hole circle
			(at -2.54 2.54)
			(size 2.286 2.286)
			(drill 1.6002)
			(layers "*.Cu" "*.Mask")
			(remove_unused_layers no)
			(net "SG")
			(padstack
				(mode front_inner_back)
				(layer "Inner"
					(shape circle)
					(size 2.286 2.286)
					(clearance -0.0508)
				)
				(layer "B.Cu"
					(shape circle)
					(size 2.286 2.286)
				)
			)
		)
		(pad "GH4" thru_hole circle
			(at 2.54 2.54)
			(size 2.286 2.286)
			(drill 1.6002)
			(layers "*.Cu" "*.Mask")
			(remove_unused_layers no)
			(net "SG")
			(padstack
				(mode front_inner_back)
				(layer "Inner"
					(shape circle)
					(size 2.286 2.286)
					(clearance -0.0508)
				)
				(layer "B.Cu"
					(shape circle)
					(size 2.286 2.286)
				)
			)
		)
	)
	(footprint ""
		(layer "F.Cu")
		(at 49.784 -131.699)
		(property "Reference" "SP73"
			(at 0 0 0)
			(layer "F.SilkS")
			(hide yes)
			(effects
				(font
					(size 1.27 1.27)
				)
			)
		)
		(property "Value" ""
			(at 0 0 0)
			(layer "F.Fab")
			(effects
				(font
					(size 1.27 1.27)
				)
			)
		)
		(duplicate_pad_numbers_are_jumpers no)
	)
	(footprint ""
		(layer "F.Cu")
		(at 155.9814 -58.3946 -90)
		(property "Reference" "C40"
			(at -3.3274 -0.26797 90)
			(unlocked yes)
			(layer "F.SilkS")
			(effects
				(font
					(size 0.7874 0.5842)
					(thickness 0.1524)
				)
			)
		)
		(property "Value" "VAL*"
			(at 0.0762 2.067306 270)
			(unlocked yes)
			(layer "F.Fab")
			(hide yes)
			(effects
				(font
					(size 0.7874 0.5842)
					(thickness 0.1524)
				)
			)
		)
		(property "Device Type" "CAPACITOR-G105-0B104-EK,0.1UF,A"
			(at 0.0508 1.127506 270)
			(unlocked yes)
			(layer "F.Fab")
			(hide yes)
			(effects
				(font
					(size 0.7874 0.5842)
					(thickness 0.1524)
				)
			)
		)
		(property "User Part Number" "PARTNUM*"
			(at 0.1016 4.023106 270)
			(unlocked yes)
			(layer "Cmts.User")
			(hide yes)
			(effects
				(font
					(size 0.7874 0.5842)
					(thickness 0.1524)
				)
			)
		)
		(property "Tolerance" "TOL*"
			(at 0.0762 3.032506 270)
			(unlocked yes)
			(layer "Cmts.User")
			(hide yes)
			(effects
				(font
					(size 0.7874 0.5842)
					(thickness 0.1524)
				)
			)
		)
		(duplicate_pad_numbers_are_jumpers no)
		(fp_line
			(start -1.143 0.5588)
			(end 1.143 0.5588)
			(stroke
				(width 0.1)
				(type default)
			)
			(layer "F.SilkS")
		)
		(fp_line
			(start 1.143 0.5588)
			(end 1.143 -0.5588)
			(stroke
				(width 0.1)
				(type default)
			)
			(layer "F.SilkS")
		)
		(fp_line
			(start -1.143 -0.5588)
			(end -1.143 0.5588)
			(stroke
				(width 0.1)
				(type default)
			)
			(layer "F.SilkS")
		)
		(fp_line
			(start 1.143 -0.5588)
			(end -1.143 -0.5588)
			(stroke
				(width 0.1)
				(type default)
			)
			(layer "F.SilkS")
		)
		(fp_rect
			(start -1.143 0.5588)
			(end 1.143 -0.5588)
			(stroke
				(width 0)
				(type default)
			)
			(fill no)
			(layer "F.CrtYd")
		)
		(fp_line
			(start -0.508 0.3048)
			(end 0.508 0.3048)
			(stroke
				(width 0.1)
				(type default)
			)
			(layer "F.Fab")
		)
		(fp_line
			(start 0.508 0.3048)
			(end 0.508 -0.3048)
			(stroke
				(width 0.1)
				(type default)
			)
			(layer "F.Fab")
		)
		(fp_line
			(start -0.508 -0.3048)
			(end -0.508 0.3048)
			(stroke
				(width 0.1)
				(type default)
			)
			(layer "F.Fab")
		)
		(fp_line
			(start 0.508 -0.3048)
			(end -0.508 -0.3048)
			(stroke
				(width 0.1)
				(type default)
			)
			(layer "F.Fab")
		)
		(pad "1" smd rect
			(at -0.5334 0 270)
			(size 0.7112 0.6096)
			(layers "F.Cu" "F.Mask" "F.Paste")
			(net "XP3R3V_FPGA")
		)
		(pad "2" smd rect
			(at 0.5334 0 270)
			(size 0.7112 0.6096)
			(layers "F.Cu" "F.Mask" "F.Paste")
			(net "SG")
		)
		(zone
			(layer "F.Cu")
			(hatch none 0.5)
			(connect_pads
				(clearance 0)
			)
			(min_thickness 0.25)
			(keepout
				(tracks allowed)
				(vias not_allowed)
				(pads allowed)
				(copperpour not_allowed)
				(footprints allowed)
			)
			(placement
				(enabled no)
				(sheetname "")
			)
			(fill
				(thermal_gap 0.5)
				(thermal_bridge_width 0.5)
				(island_removal_mode 0)
			)
			(polygon
				(pts
					(xy 155.6766 -58.4708) (xy 155.6766 -58.3184) (xy 156.2862 -58.3184) (xy 156.2862 -58.4708)
				)
			)
		)
	)
	(footprint ""
		(layer "F.Cu")
		(at 135.89 -46.228 90)
		(property "Reference" "C270"
			(at 3.302 -0.35433 90)
			(unlocked yes)
			(layer "F.SilkS")
			(effects
				(font
					(size 0.7874 0.5842)
					(thickness 0.1524)
				)
			)
		)
		(property "Value" "VAL*"
			(at 0.0762 3.134106 90)
			(unlocked yes)
			(layer "F.Fab")
			(hide yes)
			(effects
				(font
					(size 0.7874 0.5842)
					(thickness 0.1524)
				)
			)
		)
		(property "Device Type" "CAPACITOR-G107-0F476-AM,47UF,2A"
			(at 0.0508 2.194306 90)
			(unlocked yes)
			(layer "F.Fab")
			(hide yes)
			(effects
				(font
					(size 0.7874 0.5842)
					(thickness 0.1524)
				)
			)
		)
		(property "User Part Number" "PARTNUM*"
			(at 0.1016 5.013706 90)
			(unlocked yes)
			(layer "Cmts.User")
			(hide yes)
			(effects
				(font
					(size 0.7874 0.5842)
					(thickness 0.1524)
				)
			)
		)
		(property "Tolerance" "TOL*"
			(at 0.0762 4.048506 90)
			(unlocked yes)
			(layer "Cmts.User")
			(hide yes)
			(effects
				(font
					(size 0.7874 0.5842)
					(thickness 0.1524)
				)
			)
		)
		(duplicate_pad_numbers_are_jumpers no)
		(fp_line
			(start 1.5748 -0.9398)
			(end -1.5748 -0.9398)
			(stroke
				(width 0.1)
				(type default)
			)
			(layer "F.SilkS")
		)
		(fp_line
			(start -1.5748 -0.9398)
			(end -1.5748 0.9398)
			(stroke
				(width 0.1)
				(type default)
			)
			(layer "F.SilkS")
		)
		(fp_line
			(start 1.5748 0.9398)
			(end 1.5748 -0.9398)
			(stroke
				(width 0.1)
				(type default)
			)
			(layer "F.SilkS")
		)
		(fp_line
			(start -1.5748 0.9398)
			(end 1.5748 0.9398)
			(stroke
				(width 0.1)
				(type default)
			)
			(layer "F.SilkS")
		)
		(fp_rect
			(start -1.5748 -0.9398)
			(end 1.5748 0.9398)
			(stroke
				(width 0)
				(type default)
			)
			(fill no)
			(layer "F.CrtYd")
		)
		(fp_line
			(start 1.016 -0.635)
			(end -1.016 -0.635)
			(stroke
				(width 0.1)
				(type default)
			)
			(layer "F.Fab")
		)
		(fp_line
			(start -1.016 -0.635)
			(end -1.016 0.635)
			(stroke
				(width 0.1)
				(type default)
			)
			(layer "F.Fab")
		)
		(fp_line
			(start 1.016 0.635)
			(end 1.016 -0.635)
			(stroke
				(width 0.1)
				(type default)
			)
			(layer "F.Fab")
		)
		(fp_line
			(start -1.016 0.635)
			(end 1.016 0.635)
			(stroke
				(width 0.1)
				(type default)
			)
			(layer "F.Fab")
		)
		(pad "1" smd rect
			(at -0.8382 0 90)
			(size 0.9652 1.3716)
			(layers "F.Cu" "F.Mask" "F.Paste")
			(net "XP1R0V_FPGA")
		)
		(pad "2" smd rect
			(at 0.8382 0 90)
			(size 0.9652 1.3716)
			(layers "F.Cu" "F.Mask" "F.Paste")
			(net "SG")
		)
		(zone
			(layer "F.Cu")
			(hatch none 0.5)
			(connect_pads
				(clearance 0)
			)
			(min_thickness 0.25)
			(keepout
				(tracks allowed)
				(vias not_allowed)
				(pads allowed)
				(copperpour not_allowed)
				(footprints allowed)
			)
			(placement
				(enabled no)
				(sheetname "")
			)
			(fill
				(thermal_gap 0.5)
				(thermal_bridge_width 0.5)
				(island_removal_mode 0)
			)
			(polygon
				(pts
					(xy 135.255 -45.9994) (xy 136.525 -45.9994) (xy 136.525 -46.4566) (xy 135.255 -46.4566)
				)
			)
		)
	)
	(footprint ""
		(layer "F.Cu")
		(at 82.296 -76.454 -90)
		(property "Reference" "TP2"
			(at 0 0 270)
			(layer "F.SilkS")
			(hide yes)
			(effects
				(font
					(size 1.27 1.27)
				)
			)
		)
		(property "Value" ""
			(at 0 0 270)
			(layer "F.Fab")
			(effects
				(font
					(size 1.27 1.27)
				)
			)
		)
		(property "Device Type" "TP_PIONT-TP010CT020B030_PTH-TPA"
			(at -1.341882 0.996696 270)
			(unlocked yes)
			(layer "F.Fab")
			(hide yes)
			(effects
				(font
					(size 0.7874 0.5842)
					(thickness 0.1524)
				)
				(justify left)
			)
		)
		(duplicate_pad_numbers_are_jumpers no)
		(fp_poly
			(pts
				(arc
					(start 0 -0.889)
					(mid 0 0.889)
					(end 0 -0.889)
				)
			)
			(stroke
				(width 0)
				(type default)
			)
			(fill no)
			(layer "B.CrtYd")
		)
		(fp_poly
			(pts
				(arc
					(start 0 -0.889)
					(mid 0 0.889)
					(end 0 -0.889)
				)
			)
			(stroke
				(width 0)
				(type default)
			)
			(fill no)
			(layer "F.CrtYd")
		)
		(pad "1" thru_hole circle
			(at 0 0 270)
			(size 0.508 0.508)
			(drill 0.254)
			(layers "*.Cu" "*.Mask")
			(remove_unused_layers no)
			(net "BNO080_EVN_SCL")
			(clearance 0.1016)
			(padstack
				(mode front_inner_back)
				(layer "Inner"
					(shape circle)
					(size 0.508 0.508)
					(clearance 0.1016)
				)
				(layer "B.Cu"
					(shape circle)
					(size 0.762 0.762)
					(clearance -0.0254)
				)
			)
		)
	)
	(footprint ""
		(layer "F.Cu")
		(at 138.303 -20.193)
		(property "Reference" "TP57"
			(at -2.6162 1.43637 0)
			(unlocked yes)
			(layer "F.SilkS")
			(effects
				(font
					(size 0.7874 0.5842)
					(thickness 0.1524)
				)
				(justify left)
			)
		)
		(property "Value" ""
			(at 0 0 0)
			(layer "F.Fab")
			(effects
				(font
					(size 1.27 1.27)
				)
			)
		)
		(property "Device Type" "TP_PIONT-TP010CT020B030_PTH-TPA"
			(at -1.341882 0.996696 0)
			(unlocked yes)
			(layer "F.Fab")
			(hide yes)
			(effects
				(font
					(size 0.7874 0.5842)
					(thickness 0.1524)
				)
				(justify left)
			)
		)
		(duplicate_pad_numbers_are_jumpers no)
		(fp_poly
			(pts
				(arc
					(start 0.889 0)
					(mid -0.889 0)
					(end 0.889 0)
				)
			)
			(stroke
				(width 0)
				(type default)
			)
			(fill no)
			(layer "B.CrtYd")
		)
		(fp_poly
			(pts
				(arc
					(start 0.889 0)
					(mid -0.889 0)
					(end 0.889 0)
				)
			)
			(stroke
				(width 0)
				(type default)
			)
			(fill no)
			(layer "F.CrtYd")
		)
		(pad "1" thru_hole circle
			(at 0 0)
			(size 0.508 0.508)
			(drill 0.254)
			(layers "*.Cu" "*.Mask")
			(remove_unused_layers no)
			(net "XP2R5V_FPGA")
			(clearance 0.1016)
			(padstack
				(mode front_inner_back)
				(layer "Inner"
					(shape circle)
					(size 0.508 0.508)
					(clearance 0.1016)
				)
				(layer "B.Cu"
					(shape circle)
					(size 0.762 0.762)
					(clearance -0.0254)
				)
			)
		)
	)
	(footprint ""
		(layer "F.Cu")
		(at 26.035 -75.184 90)
		(property "Reference" "R480"
			(at -3.175 0.54737 90)
			(unlocked yes)
			(layer "F.SilkS")
			(effects
				(font
					(size 0.7874 0.5842)
					(thickness 0.1524)
				)
			)
		)
		(property "Value" "VAL*"
			(at 0.02032 2.13233 90)
			(unlocked yes)
			(layer "F.Fab")
			(hide yes)
			(effects
				(font
					(size 0.7874 0.5842)
					(thickness 0.1524)
				)
			)
		)
		(property "Tolerance" "TOL*"
			(at 0.044704 3.05435 90)
			(unlocked yes)
			(layer "Cmts.User")
			(hide yes)
			(effects
				(font
					(size 0.7874 0.5842)
					(thickness 0.1524)
				)
			)
		)
		(property "User Part Number" "PARTNUM*"
			(at 0.02032 4.024884 90)
			(unlocked yes)
			(layer "Cmts.User")
			(hide yes)
			(effects
				(font
					(size 0.7874 0.5842)
					(thickness 0.1524)
				)
			)
		)
		(property "Device Type" "RESISTOR-G155-11003-01,100KOHMA"
			(at 0.008382 1.210564 90)
			(unlocked yes)
			(layer "F.Fab")
			(hide yes)
			(effects
				(font
					(size 0.7874 0.5842)
					(thickness 0.1524)
				)
			)
		)
		(duplicate_pad_numbers_are_jumpers no)
		(fp_line
			(start 1.143 -0.5588)
			(end -1.143 -0.5588)
			(stroke
				(width 0.1)
				(type default)
			)
			(layer "F.SilkS")
		)
		(fp_line
			(start -1.143 -0.5588)
			(end -1.143 0.5588)
			(stroke
				(width 0.1)
				(type default)
			)
			(layer "F.SilkS")
		)
		(fp_line
			(start 1.143 0.5588)
			(end 1.143 -0.5588)
			(stroke
				(width 0.1)
				(type default)
			)
			(layer "F.SilkS")
		)
		(fp_line
			(start -1.143 0.5588)
			(end 1.143 0.5588)
			(stroke
				(width 0.1)
				(type default)
			)
			(layer "F.SilkS")
		)
		(fp_poly
			(pts
				(xy -1.143 0.5588) (xy 1.143 0.5588) (xy 1.143 -0.5588) (xy -1.143 -0.5588)
			)
			(stroke
				(width 0)
				(type default)
			)
			(fill no)
			(layer "F.CrtYd")
		)
		(fp_line
			(start 0.508 -0.3048)
			(end -0.508 -0.3048)
			(stroke
				(width 0.1)
				(type default)
			)
			(layer "F.Fab")
		)
		(fp_line
			(start -0.508 -0.3048)
			(end -0.508 0.3048)
			(stroke
				(width 0.1)
				(type default)
			)
			(layer "F.Fab")
		)
		(fp_line
			(start 0.508 0.3048)
			(end 0.508 -0.3048)
			(stroke
				(width 0.1)
				(type default)
			)
			(layer "F.Fab")
		)
		(fp_line
			(start -0.508 0.3048)
			(end 0.508 0.3048)
			(stroke
				(width 0.1)
				(type default)
			)
			(layer "F.Fab")
		)
		(pad "1" smd rect
			(at -0.5334 0 90)
			(size 0.7112 0.6096)
			(layers "F.Cu" "F.Mask" "F.Paste")
			(net "UART_FT4232_TX_FPGA_RX")
		)
		(pad "2" smd rect
			(at 0.5334 0 90)
			(size 0.7112 0.6096)
			(layers "F.Cu" "F.Mask" "F.Paste")
			(net "XP3R3V_FT4232")
		)
		(zone
			(layer "F.Cu")
			(hatch none 0.5)
			(connect_pads
				(clearance 0)
			)
			(min_thickness 0.25)
			(keepout
				(tracks allowed)
				(vias not_allowed)
				(pads allowed)
				(copperpour not_allowed)
				(footprints allowed)
			)
			(placement
				(enabled no)
				(sheetname "")
			)
			(fill
				(thermal_gap 0.5)
				(thermal_bridge_width 0.5)
				(island_removal_mode 0)
			)
			(polygon
				(pts
					(xy 26.3398 -75.1078) (xy 26.3398 -75.2602) (xy 25.7302 -75.2602) (xy 25.7302 -75.1078)
				)
			)
		)
		(zone
			(layer "F.Cu")
			(hatch none 0.5)
			(connect_pads
				(clearance 0)
			)
			(min_thickness 0.25)
			(keepout
				(tracks not_allowed)
				(vias allowed)
				(pads allowed)
				(copperpour not_allowed)
				(footprints allowed)
			)
			(placement
				(enabled no)
				(sheetname "")
			)
			(fill
				(thermal_gap 0.5)
				(thermal_bridge_width 0.5)
				(island_removal_mode 0)
			)
			(polygon
				(pts
					(xy 26.3398 -75.1078) (xy 26.3398 -75.2602) (xy 25.7302 -75.2602) (xy 25.7302 -75.1078)
				)
			)
		)
	)
)
